(kicad_pcb
	(version 20241229)
	(generator "pcbnew")
	(generator_version "9.0")
	(general
		(thickness 1.258)
		(legacy_teardrops no)
	)
	(paper "A4")
	(title_block
		(date "2024-05-27")
		(rev "1.1.2")
		(comment 9 "footprints 19-25 of 64")
	)
	(layers
		(0 "F.Cu" signal)
		(4 "In1.Cu" power)
		(6 "In2.Cu" power)
		(8 "In3.Cu" signal)
		(10 "In4.Cu" signal)
		(2 "B.Cu" signal)
		(9 "F.Adhes" user "F.Adhesive")
		(11 "B.Adhes" user "B.Adhesive")
		(13 "F.Paste" user)
		(15 "B.Paste" user)
		(5 "F.SilkS" user "F.Silkscreen")
		(7 "B.SilkS" user "B.Silkscreen")
		(1 "F.Mask" user)
		(3 "B.Mask" user)
		(17 "Dwgs.User" user "User.Drawings")
		(19 "Cmts.User" user "User.Comments")
		(21 "Eco1.User" user "User.Eco1")
		(23 "Eco2.User" user "User.Eco2")
		(25 "Edge.Cuts" user)
		(27 "Margin" user)
		(31 "F.CrtYd" user "F.Courtyard")
		(29 "B.CrtYd" user "B.Courtyard")
		(35 "F.Fab" user)
		(33 "B.Fab" user)
	)
	(footprint "antmicro-footprints:R_0402_1005Metric"
		(layer "F.Cu")
		(at 127.441666 75.95 90)
		(descr "Resistor SMD 0402")
		(tags "resistor SMD 0402")
		(property "Reference" "R10"
			(at -3.05 0.345 90)
			(layer "F.SilkS")
			(effects
				(font
					(size 0.7 0.7)
					(thickness 0.15)
				)
				(justify left bottom)
			)
		)
		(property "Value" "R_220R_0402"
			(at 0 1.4 90)
			(layer "F.Fab")
			(hide yes)
			(effects
				(font
					(size 0.7 0.7)
					(thickness 0.15)
				)
				(justify left bottom)
			)
		)
		(property "Description" "220R resistor in 0402 package with 1% tolerance"
			(at 0 0 90)
			(layer "F.Fab")
			(hide yes)
			(effects
				(font
					(size 1.27 1.27)
					(thickness 0.15)
				)
			)
		)
		(property "Author" "Antmicro"
			(at 203.391666 -51.491666 0)
			(layer "F.Fab")
			(hide yes)
			(effects
				(font
					(size 1 1)
					(thickness 0.15)
				)
			)
		)
		(property "License" "Apache-2.0"
			(at 203.391666 -51.491666 0)
			(layer "F.Fab")
			(hide yes)
			(effects
				(font
					(size 1 1)
					(thickness 0.15)
				)
			)
		)
		(property "MPN" "CR0402-FX-2200GLF"
			(at 203.391666 -51.491666 0)
			(layer "F.Fab")
			(hide yes)
			(effects
				(font
					(size 1 1)
					(thickness 0.15)
				)
			)
		)
		(property "Manufacturer" "Bourns"
			(at 203.391666 -51.491666 0)
			(layer "F.Fab")
			(hide yes)
			(effects
				(font
					(size 1 1)
					(thickness 0.15)
				)
			)
		)
		(property "Tolerance" "1%"
			(at 203.391666 -51.491666 0)
			(layer "F.Fab")
			(hide yes)
			(effects
				(font
					(size 1 1)
					(thickness 0.15)
				)
			)
		)
		(property "Val" "220R"
			(at 203.391666 -51.491666 0)
			(layer "F.Fab")
			(hide yes)
			(effects
				(font
					(size 1 1)
					(thickness 0.15)
				)
			)
		)
		(sheetname "EEPROM")
		(sheetfile "EEPROM.kicad_sch")
		(attr smd)
		(fp_rect
			(start -0.925 -0.47)
			(end 0.925 0.47)
			(stroke
				(width 0.05)
				(type default)
			)
			(fill no)
			(layer "F.CrtYd")
		)
		(fp_rect
			(start -0.5 -0.25)
			(end 0.5 0.25)
			(stroke
				(width 0.15)
				(type solid)
			)
			(fill no)
			(layer "F.Fab")
		)
		(pad "1" smd roundrect
			(at -0.48 0 90)
			(size 0.59 0.64)
			(layers "F.Cu" "F.Mask" "F.Paste")
			(roundrect_rratio 0.25)
			(net 9 "Net-(IC1-P1)")
			(pintype "passive")
		)
		(pad "2" smd roundrect
			(at 0.48 0 90)
			(size 0.59 0.64)
			(layers "F.Cu" "F.Mask" "F.Paste")
			(roundrect_rratio 0.25)
			(net 5 "Net-(D2-Pad1)")
			(pintype "passive")
		)
	)
	(footprint "antmicro-footprints:R_0402_1005Metric"
		(layer "F.Cu")
		(at 129.258332 75.95 90)
		(descr "Resistor SMD 0402")
		(tags "resistor SMD 0402")
		(property "Reference" "R11"
			(at -3.05 0.345 90)
			(layer "F.SilkS")
			(effects
				(font
					(size 0.7 0.7)
					(thickness 0.15)
				)
				(justify left bottom)
			)
		)
		(property "Value" "R_220R_0402"
			(at 0 1.4 90)
			(layer "F.Fab")
			(hide yes)
			(effects
				(font
					(size 0.7 0.7)
					(thickness 0.15)
				)
				(justify left bottom)
			)
		)
		(property "Description" "220R resistor in 0402 package with 1% tolerance"
			(at 0 0 90)
			(layer "F.Fab")
			(hide yes)
			(effects
				(font
					(size 1.27 1.27)
					(thickness 0.15)
				)
			)
		)
		(property "Author" "Antmicro"
			(at 205.208332 -53.308332 0)
			(layer "F.Fab")
			(hide yes)
			(effects
				(font
					(size 1 1)
					(thickness 0.15)
				)
			)
		)
		(property "License" "Apache-2.0"
			(at 205.208332 -53.308332 0)
			(layer "F.Fab")
			(hide yes)
			(effects
				(font
					(size 1 1)
					(thickness 0.15)
				)
			)
		)
		(property "MPN" "CR0402-FX-2200GLF"
			(at 205.208332 -53.308332 0)
			(layer "F.Fab")
			(hide yes)
			(effects
				(font
					(size 1 1)
					(thickness 0.15)
				)
			)
		)
		(property "Manufacturer" "Bourns"
			(at 205.208332 -53.308332 0)
			(layer "F.Fab")
			(hide yes)
			(effects
				(font
					(size 1 1)
					(thickness 0.15)
				)
			)
		)
		(property "Tolerance" "1%"
			(at 205.208332 -53.308332 0)
			(layer "F.Fab")
			(hide yes)
			(effects
				(font
					(size 1 1)
					(thickness 0.15)
				)
			)
		)
		(property "Val" "220R"
			(at 205.208332 -53.308332 0)
			(layer "F.Fab")
			(hide yes)
			(effects
				(font
					(size 1 1)
					(thickness 0.15)
				)
			)
		)
		(sheetname "EEPROM")
		(sheetfile "EEPROM.kicad_sch")
		(attr smd)
		(fp_rect
			(start -0.925 -0.47)
			(end 0.925 0.47)
			(stroke
				(width 0.05)
				(type default)
			)
			(fill no)
			(layer "F.CrtYd")
		)
		(fp_rect
			(start -0.5 -0.25)
			(end 0.5 0.25)
			(stroke
				(width 0.15)
				(type solid)
			)
			(fill no)
			(layer "F.Fab")
		)
		(pad "1" smd roundrect
			(at -0.48 0 90)
			(size 0.59 0.64)
			(layers "F.Cu" "F.Mask" "F.Paste")
			(roundrect_rratio 0.25)
			(net 10 "Net-(IC1-P2)")
			(pintype "passive")
		)
		(pad "2" smd roundrect
			(at 0.48 0 90)
			(size 0.59 0.64)
			(layers "F.Cu" "F.Mask" "F.Paste")
			(roundrect_rratio 0.25)
			(net 6 "Net-(D3-Pad1)")
			(pintype "passive")
		)
	)
	(footprint "antmicro-footprints:TP_SMD_1mm"
		(layer "F.Cu")
		(at 127.975 88.55)
		(property "Reference" "TP1"
			(at -2.515 0.05 0)
			(layer "F.SilkS")
			(effects
				(font
					(size 0.7 0.7)
					(thickness 0.15)
				)
				(justify left bottom)
			)
		)
		(property "Value" "TP_1mm_SMD"
			(at 0 1.4 0)
			(layer "F.Fab")
			(hide yes)
			(effects
				(font
					(size 0.7 0.7)
					(thickness 0.15)
				)
				(justify left bottom)
			)
		)
		(property "Description" "Test Point 1mm"
			(at 0 0 0)
			(layer "F.Fab")
			(hide yes)
			(effects
				(font
					(size 1.27 1.27)
					(thickness 0.15)
				)
			)
		)
		(property "Author" "Antmicro"
			(at 0 0 0)
			(layer "F.Fab")
			(hide yes)
			(effects
				(font
					(size 1 1)
					(thickness 0.15)
				)
			)
		)
		(property "License" "Apache-2.0"
			(at 0 0 0)
			(layer "F.Fab")
			(hide yes)
			(effects
				(font
					(size 1 1)
					(thickness 0.15)
				)
			)
		)
		(property "MPN" ""
			(at 0 0 0)
			(layer "F.Fab")
			(hide yes)
			(effects
				(font
					(size 1 1)
					(thickness 0.15)
				)
			)
		)
		(property "Manufacturer" ""
			(at 0 0 0)
			(layer "F.Fab")
			(hide yes)
			(effects
				(font
					(size 1 1)
					(thickness 0.15)
				)
			)
		)
		(sheetname "EEPROM")
		(sheetfile "EEPROM.kicad_sch")
		(attr exclude_from_pos_files)
		(pad "1" smd circle
			(at 0 0)
			(size 1 1)
			(layers "F.Cu" "F.Mask")
			(net 14 "Net-(IC1-P4)")
			(pinfunction "1")
			(pintype "passive")
		)
	)
	(footprint "antmicro-footprints:C_0402_1005Metric"
		(layer "F.Cu")
		(at 132.175 91.615 90)
		(descr "Capacitor SMD 0402")
		(tags "capacitor SMD 0402")
		(property "Reference" "C39"
			(at -1.275 1.335 90)
			(layer "F.SilkS")
			(effects
				(font
					(size 0.7 0.7)
					(thickness 0.15)
				)
				(justify left bottom)
			)
		)
		(property "Value" "C_100n_0402"
			(at 0 1.4 90)
			(layer "F.Fab")
			(hide yes)
			(effects
				(font
					(size 0.7 0.7)
					(thickness 0.15)
				)
				(justify left bottom)
			)
		)
		(property "Description" " "
			(at 0 0 90)
			(layer "F.Fab")
			(hide yes)
			(effects
				(font
					(size 1.27 1.27)
					(thickness 0.15)
				)
			)
		)
		(property "Author" "Antmicro"
			(at 223.79 -40.56 0)
			(layer "F.Fab")
			(hide yes)
			(effects
				(font
					(size 1 1)
					(thickness 0.15)
				)
			)
		)
		(property "Dielectric" "X5R"
			(at 223.79 -40.56 0)
			(layer "F.Fab")
			(hide yes)
			(effects
				(font
					(size 1 1)
					(thickness 0.15)
				)
			)
		)
		(property "License" "Apache-2.0"
			(at 223.79 -40.56 0)
			(layer "F.Fab")
			(hide yes)
			(effects
				(font
					(size 1 1)
					(thickness 0.15)
				)
			)
		)
		(property "MPN" "GRM155R61H104KE14D"
			(at 223.79 -40.56 0)
			(layer "F.Fab")
			(hide yes)
			(effects
				(font
					(size 1 1)
					(thickness 0.15)
				)
			)
		)
		(property "Manufacturer" "Murata"
			(at 223.79 -40.56 0)
			(layer "F.Fab")
			(hide yes)
			(effects
				(font
					(size 1 1)
					(thickness 0.15)
				)
			)
		)
		(property "Val" "100n"
			(at 223.79 -40.56 0)
			(layer "F.Fab")
			(hide yes)
			(effects
				(font
					(size 1 1)
					(thickness 0.15)
				)
			)
		)
		(property "Voltage" "50V"
			(at 223.79 -40.56 0)
			(layer "F.Fab")
			(hide yes)
			(effects
				(font
					(size 1 1)
					(thickness 0.15)
				)
			)
		)
		(sheetname "EEPROM")
		(sheetfile "EEPROM.kicad_sch")
		(attr smd)
		(fp_rect
			(start -0.925 -0.47)
			(end 0.925 0.47)
			(stroke
				(width 0.05)
				(type default)
			)
			(fill no)
			(layer "F.CrtYd")
		)
		(fp_line
			(start 0.504 -0.25)
			(end 0.504 0.248)
			(stroke
				(width 0.15)
				(type solid)
			)
			(layer "F.Fab")
		)
		(fp_line
			(start -0.494 -0.25)
			(end 0.504 -0.25)
			(stroke
				(width 0.15)
				(type solid)
			)
			(layer "F.Fab")
		)
		(fp_line
			(start 0.504 0.248)
			(end -0.494 0.248)
			(stroke
				(width 0.15)
				(type solid)
			)
			(layer "F.Fab")
		)
		(fp_line
			(start -0.494 0.248)
			(end -0.494 -0.25)
			(stroke
				(width 0.15)
				(type solid)
			)
			(layer "F.Fab")
		)
		(pad "1" smd roundrect
			(at -0.48 0 90)
			(size 0.59 0.64)
			(layers "F.Cu" "F.Mask" "F.Paste")
			(roundrect_rratio 0.25)
			(net 50 "1V8_SYS")
			(pintype "passive")
		)
		(pad "2" smd roundrect
			(at 0.48 0 90)
			(size 0.59 0.64)
			(layers "F.Cu" "F.Mask" "F.Paste")
			(roundrect_rratio 0.25)
			(net 1 "GND")
			(pintype "passive")
		)
	)
	(footprint "antmicro-footprints:R_0402_1005Metric"
		(layer "F.Cu")
		(at 126.56 92.585 90)
		(descr "Resistor SMD 0402")
		(tags "resistor SMD 0402")
		(property "Reference" "R13"
			(at -1.015 -0.67 90)
			(layer "F.SilkS")
			(effects
				(font
					(size 0.7 0.7)
					(thickness 0.15)
				)
				(justify left bottom)
			)
		)
		(property "Value" "R_10k_0402"
			(at 0 1.4 90)
			(layer "F.Fab")
			(hide yes)
			(effects
				(font
					(size 0.7 0.7)
					(thickness 0.15)
				)
				(justify left bottom)
			)
		)
		(property "Description" "10k resistor in 0402 package with 1% tolerance"
			(at 0 0 90)
			(layer "F.Fab")
			(hide yes)
			(effects
				(font
					(size 1.27 1.27)
					(thickness 0.15)
				)
			)
		)
		(property "Author" "Antmicro"
			(at 219.145 -33.975 0)
			(layer "F.Fab")
			(hide yes)
			(effects
				(font
					(size 1 1)
					(thickness 0.15)
				)
			)
		)
		(property "License" "Apache-2.0"
			(at 219.145 -33.975 0)
			(layer "F.Fab")
			(hide yes)
			(effects
				(font
					(size 1 1)
					(thickness 0.15)
				)
			)
		)
		(property "MPN" "CR0402-FX-1002GLF"
			(at 219.145 -33.975 0)
			(layer "F.Fab")
			(hide yes)
			(effects
				(font
					(size 1 1)
					(thickness 0.15)
				)
			)
		)
		(property "Manufacturer" "Bourns"
			(at 219.145 -33.975 0)
			(layer "F.Fab")
			(hide yes)
			(effects
				(font
					(size 1 1)
					(thickness 0.15)
				)
			)
		)
		(property "Tolerance" "1%"
			(at 219.145 -33.975 0)
			(layer "F.Fab")
			(hide yes)
			(effects
				(font
					(size 1 1)
					(thickness 0.15)
				)
			)
		)
		(property "Val" "10k"
			(at 219.145 -33.975 0)
			(layer "F.Fab")
			(hide yes)
			(effects
				(font
					(size 1 1)
					(thickness 0.15)
				)
			)
		)
		(sheetname "EEPROM")
		(sheetfile "EEPROM.kicad_sch")
		(attr smd)
		(fp_rect
			(start -0.925 -0.47)
			(end 0.925 0.47)
			(stroke
				(width 0.05)
				(type default)
			)
			(fill no)
			(layer "F.CrtYd")
		)
		(fp_rect
			(start -0.5 -0.25)
			(end 0.5 0.25)
			(stroke
				(width 0.15)
				(type solid)
			)
			(fill no)
			(layer "F.Fab")
		)
		(pad "1" smd roundrect
			(at -0.48 0 90)
			(size 0.59 0.64)
			(layers "F.Cu" "F.Mask" "F.Paste")
			(roundrect_rratio 0.25)
			(net 50 "1V8_SYS")
			(pintype "passive")
		)
		(pad "2" smd roundrect
			(at 0.48 0 90)
			(size 0.59 0.64)
			(layers "F.Cu" "F.Mask" "F.Paste")
			(roundrect_rratio 0.25)
			(net 12 "SDA")
			(pintype "passive")
		)
	)
	(footprint "antmicro-footprints:R_0402_1005Metric"
		(layer "F.Cu")
		(at 126.555 89.72 -90)
		(descr "Resistor SMD 0402")
		(tags "resistor SMD 0402")
		(property "Reference" "R14"
			(at 1.04 0.635 270)
			(layer "F.SilkS")
			(effects
				(font
					(size 0.7 0.7)
					(thickness 0.15)
				)
				(justify left bottom)
			)
		)
		(property "Value" "R_10k_0402"
			(at 0 1.4 270)
			(layer "F.Fab")
			(hide yes)
			(effects
				(font
					(size 0.7 0.7)
					(thickness 0.15)
				)
				(justify left bottom)
			)
		)
		(property "Description" "10k resistor in 0402 package with 1% tolerance"
			(at 0 0 270)
			(layer "F.Fab")
			(hide yes)
			(effects
				(font
					(size 1.27 1.27)
					(thickness 0.15)
				)
			)
		)
		(property "Author" "Antmicro"
			(at 36.835 216.275 0)
			(layer "F.Fab")
			(hide yes)
			(effects
				(font
					(size 1 1)
					(thickness 0.15)
				)
			)
		)
		(property "License" "Apache-2.0"
			(at 36.835 216.275 0)
			(layer "F.Fab")
			(hide yes)
			(effects
				(font
					(size 1 1)
					(thickness 0.15)
				)
			)
		)
		(property "MPN" "CR0402-FX-1002GLF"
			(at 36.835 216.275 0)
			(layer "F.Fab")
			(hide yes)
			(effects
				(font
					(size 1 1)
					(thickness 0.15)
				)
			)
		)
		(property "Manufacturer" "Bourns"
			(at 36.835 216.275 0)
			(layer "F.Fab")
			(hide yes)
			(effects
				(font
					(size 1 1)
					(thickness 0.15)
				)
			)
		)
		(property "Tolerance" "1%"
			(at 36.835 216.275 0)
			(layer "F.Fab")
			(hide yes)
			(effects
				(font
					(size 1 1)
					(thickness 0.15)
				)
			)
		)
		(property "Val" "10k"
			(at 36.835 216.275 0)
			(layer "F.Fab")
			(hide yes)
			(effects
				(font
					(size 1 1)
					(thickness 0.15)
				)
			)
		)
		(sheetname "EEPROM")
		(sheetfile "EEPROM.kicad_sch")
		(attr smd)
		(fp_rect
			(start -0.925 -0.47)
			(end 0.925 0.47)
			(stroke
				(width 0.05)
				(type default)
			)
			(fill no)
			(layer "F.CrtYd")
		)
		(fp_rect
			(start -0.5 -0.25)
			(end 0.5 0.25)
			(stroke
				(width 0.15)
				(type solid)
			)
			(fill no)
			(layer "F.Fab")
		)
		(pad "1" smd roundrect
			(at -0.48 0 270)
			(size 0.59 0.64)
			(layers "F.Cu" "F.Mask" "F.Paste")
			(roundrect_rratio 0.25)
			(net 50 "1V8_SYS")
			(pintype "passive")
		)
		(pad "2" smd roundrect
			(at 0.48 0 270)
			(size 0.59 0.64)
			(layers "F.Cu" "F.Mask" "F.Paste")
			(roundrect_rratio 0.25)
			(net 13 "SCL")
			(pintype "passive")
		)
	)
	(footprint "antmicro-footprints:FB_0805_2012Metric"
		(layer "F.Cu")
		(at 138.2 87.2)
		(descr "FERRITE BEAD 0805")
		(tags "FERRITE BEAD 0805")
		(property "Reference" "FB1"
			(at 1.81 0.41 0)
			(layer "F.SilkS")
			(effects
				(font
					(size 0.7 0.7)
					(thickness 0.15)
				)
				(justify left bottom)
			)
		)
		(property "Value" "FB_220Z_1.5A_WE-CBF_0805"
			(at 0 1.8 0)
			(layer "F.Fab")
			(hide yes)
			(effects
				(font
					(size 0.7 0.7)
					(thickness 0.15)
				)
				(justify left bottom)
			)
		)
		(property "Description" "Ferrite Bead, 0805 [2012 Metric], 220 ohm, 2 A, WE-CBF, 0.05 ohm, ± 25%, High Current"
			(at 0 0 0)
			(layer "F.Fab")
			(hide yes)
			(effects
				(font
					(size 1.27 1.27)
					(thickness 0.15)
				)
			)
		)
		(property "Author" "Antmicro"
			(at 0 0 0)
			(layer "F.Fab")
			(hide yes)
			(effects
				(font
					(size 1 1)
					(thickness 0.15)
				)
			)
		)
		(property "Current" "1.5A"
			(at 0 0 0)
			(layer "F.Fab")
			(hide yes)
			(effects
				(font
					(size 1 1)
					(thickness 0.15)
				)
			)
		)
		(property "License" "Apache-2.0"
			(at 0 0 0)
			(layer "F.Fab")
			(hide yes)
			(effects
				(font
					(size 1 1)
					(thickness 0.15)
				)
			)
		)
		(property "MPN" "742792022"
			(at 0 0 0)
			(layer "F.Fab")
			(hide yes)
			(effects
				(font
					(size 1 1)
					(thickness 0.15)
				)
			)
		)
		(property "Manufacturer" "Würth Elektronik"
			(at 0 0 0)
			(layer "F.Fab")
			(hide yes)
			(effects
				(font
					(size 1 1)
					(thickness 0.15)
				)
			)
		)
		(property "Public" "False"
			(at 0 0 0)
			(layer "F.Fab")
			(hide yes)
			(effects
				(font
					(size 1 1)
					(thickness 0.15)
				)
			)
		)
		(property "Val" "220Z/1.5A"
			(at 0 0 0)
			(layer "F.Fab")
			(hide yes)
			(effects
				(font
					(size 1 1)
					(thickness 0.15)
				)
			)
		)
		(sheetname "DDR5")
		(sheetfile "ddr5.kicad_sch")
		(attr smd)
		(fp_line
			(start -0.319 0.698)
			(end 0.281 0.698)
			(stroke
				(width 0.15)
				(type solid)
			)
			(layer "F.SilkS")
		)
		(fp_line
			(start -0.299 -0.698)
			(end 0.299 -0.698)
			(stroke
				(width 0.15)
				(type solid)
			)
			(layer "F.SilkS")
		)
		(fp_rect
			(start 1.95 -0.9)
			(end -1.95 0.9)
			(stroke
				(width 0.05)
				(type default)
			)
			(fill no)
			(layer "F.CrtYd")
		)
		(fp_line
			(start -0.948 -0.681)
			(end 0.948 -0.681)
			(stroke
				(width 0.15)
				(type solid)
			)
			(layer "F.Fab")
		)
		(fp_line
			(start -0.948 -0.676)
			(end -0.948 0.676)
			(stroke
				(width 0.15)
				(type solid)
			)
			(layer "F.Fab")
		)
		(fp_line
			(start -0.948 0.681)
			(end 0.948 0.681)
			(stroke
				(width 0.15)
				(type solid)
			)
			(layer "F.Fab")
		)
		(fp_line
			(start 0.948 -0.676)
			(end 0.948 0.676)
			(stroke
				(width 0.15)
				(type solid)
			)
			(layer "F.Fab")
		)
		(pad "1" smd roundrect
			(at -1.1 0)
			(size 1.2 1.3)
			(layers "F.Cu" "F.Mask" "F.Paste")
			(roundrect_rratio 0.25)
			(net 51 "1V1_SYS")
			(pintype "passive")
		)
		(pad "2" smd roundrect
			(at 1.1 0)
			(size 1.2 1.3)
			(layers "F.Cu" "F.Mask" "F.Paste")
			(roundrect_rratio 0.25)
			(net 18 "VDD")
			(pintype "passive")
		)
	)
)
